FILE_TYPE = CONNECTIVITY;
{Allegro Design Entry HDL 17.2-2016 S081 (4005846) 1/11/2022}
"PAGE_NUMBER" = 261;
0"NC";
1"PVCCFA_EHV_CPU0_PVCC";
2"PVCCFA_EHV_CPU0_PVCC";
3"SW_P12V_PVCCINFAON_CPU0_FLT\g";
4"SW_P12V_PVCCINFAON_CPU0_FLT\g";
5"PVCCINFAON_CPU0\g";
6"P12V_AUX\g";
7"PVCCINFAON_CPU0\g";
8"PVCCINFAON_CPU0\g";
9"SW_P12V_PVCCINFAON_CPU0_FLT\g";
10"PVCCINFAON_CPU0\g";
11"GND\g";
12"GND\g";
13"GND\g";
14"GND\g";
15"GND\g";
16"GND\g";
17"GND\g";
18"GND\g";
19"GND\g";
20"GND\g";
21"GND\g";
22"GND\g";
23"GND\g";
24"GND\g";
25"GND\g";
26"GND\g";
27"GND\g";
28"GND\g";
29"SW_PVCCINFAON_CPU0_BOOT1_R";
30"SW_PVCCINFAON_CPU0_BOOTR1"CDS_PHYS_NET_NAME"SW_PVCCINFAON_CPU0_BOOTR1";
31"SW_PVCCINFAON_CPU0_SW1";
32"PVCCINFAON_CPU0_VOS1";
33"SW_PVCCINFAON_CPU0_BOOT1"CDS_PHYS_NET_NAME"SW_PVCCINFAON_CPU0_BOOT1";
34"SW_PVCCINFAON_CPU0_SW2";
35"SW_PVCCINFAON_CPU0_BOOT2_R";
36"SW_PVCCINFAON_CPU0_BOOTR2"CDS_PHYS_NET_NAME"SW_PVCCINFAON_CPU0_BOOTR2";
37"SW_PVCCINFAON_CPU0_BOOT2"CDS_PHYS_NET_NAME"SW_PVCCINFAON_CPU0_BOOT2";
38"PVCCINFAON_CPU0_VOS2";
39"PVCCINFAON_CPU0_VDD1";
40"PVCCINFAON_CPU0_VREF"CDS_PHYS_NET_NAME"PVCCINFAON_CPU0_VREF";
41"PVCCINFAON_CPU0_ACSP1";
42"PVCCINFAON_CPU0_ATSEN";
43"PVCCINFAON_CPU0_LSET1";
44"PVCCINFAON_CPU0_APWM1";
45"PVCCINFAON_CPU0_VDD2";
46"PVCCINFAON_CPU0_ACSP2";
47"PVCCINFAON_CPU0_VREF"CDS_PHYS_NET_NAME"PVCCINFAON_CPU0_VREF";
48"PVCCINFAON_CPU0_ATSEN";
49"PVCCINFAON_CPU0_APWM2";
50"PVCCINFAON_CPU0_LSET2";
%"UNIVERSAL_GND"
"1","(-10900,1175)","0","logical_power","I1";
;
CDS_LIB"logical_power"
HDL_POWER"GND";
"A"11;
%"UNIVERSAL_GND"
"1","(-10400,2175)","0","logical_power","I10";
;
CDS_LIB"logical_power"
HDL_POWER"GND"
ROOM"VR_CORE0_CTRL";
"A"14;
%"Q_CAP"
"2","(-10225,1800)","0","pure_quanta","I11";
;
PART_NUMBER"CH4104K1B00"
MATERIAL"X7R"
VOLTAGE"25V"
TOLERANCE"10%"
VALUE"0.1UF"
PACK_TYPE"0402"
LOCATION"PC1346"
CDS_LIB"pure_quanta"
$SEC"1"
CDS_SEC"1";
"A"
$PN"1"12;
"B"
$PN"2"47;
%"ISL99390FRZTR5935"
"1","(-8875,1975)","0","pure_quanta","I12";
;
PART_NUMBER"AL099390004"
VALUE"ISL99390FRZ-TR5935"
MATERIAL"IC"
PART_TYPE"SMLF"
LOCATION"PU44_P0_2"
NEEDS_NO_SIZE"TRUE"
CDS_LMAN_SYM_OUTLINE"-300,700,250,-650"
CDS_LIB"pure_quanta"
SEC_TYPE""
SEC"1";
"PGND2"
$PN"7_9-20_24"19;
"GL2"
$PN"41"0;
"GL1"
$PN"6"0;
"DNC"
$PN"31"0;
"EN"
$PN"35"45;
"PGND3"
$PN"40"19;
"VOS"
$PN"1"38;
"VIN2"
$PN"30"3;
"PGND1"
$PN"5"19;
"SW"
$PN"10_19"34;
"LSET"
$PN"37"50;
"IOUT"
$PN"38"46;
"TOUT_FLT"
$PN"36"48;
"PVCC"
$PN"4"1;
"PHASE"
$PN"32"36;
"VIN1"
$PN"25_29"3;
"BOOT"
$PN"33"37;
"AGND"
$PN"2"19;
"VCC"
$PN"3"45;
"REFIN"
$PN"39"47;
"PWM"
$PN"34"49;
%"Q_CAP"
"1","(-10400,2425)","0","pure_quanta","I13";
;
PART_NUMBER"CH5222KEB01"
VALUE"2.2UF"
VOLTAGE"10V"
MATERIAL"X6S"
TOLERANCE"10%"
PACK_TYPE"C0402"
LOCATION"PC188"
CDS_LIB"pure_quanta"
LOCATION"PC188"
$SEC"1"
CDS_SEC"1";
"B"
$PN"2"14;
"A"
$PN"1"45;
%"Q_RES"
"2","(-10400,2825)","0","pure_quanta","I14";
;
PART_NUMBER"CS-2202FB01"
MATERIAL"CHIP"
WATTAGE"1/16W"
TOLERANCE"1%"
PACK_TYPE"0402LF"
VALUE"2.2"
LOCATION"PR102"
CDS_LIB"pure_quanta"
LOCATION"PR102"
$SEC"1"
CDS_SEC"1";
"A"
$PN"1"1;
"B"
$PN"2"45;
%"UNIVERSAL_GND"
"1","(-9875,2675)","0","logical_power","I15";
;
CDS_LIB"logical_power"
HDL_POWER"GND"
ROOM"VR_CORE0_CTRL";
"A"15;
%"Q_CAP"
"1","(-9875,2900)","0","pure_quanta","I16";
;
PART_NUMBER"CH5222KEB01"
VOLTAGE"10V"
TOLERANCE"10%"
VALUE"2.2UF"
PACK_TYPE"C0402"
MATERIAL"X6S"
LOCATION"PC2946"
CDS_LIB"pure_quanta"
$SEC"1"
CDS_SEC"1";
"B"
$PN"2"15;
"A"
$PN"1"1;
%"VCC15"
"1","(-10400,3350)","0","logical_power","I17";
;
HDL_POWER"PVCCFA_EHV_CPU0_PVCC"
CDS_LIB"logical_power";
"A"1;
%"Q_RES"
"2","(-10900,1400)","2","pure_quanta","I2";
;
PART_NUMBER"CS28872FB01"
WATTAGE"1/16W"
TOLERANCE"1%"
VALUE"8.87K"
PACK_TYPE"0402LF"
MATERIAL"EMPTY"
LOCATION"PR1707"
CDS_LIB"pure_quanta"
$SEC"1"
CDS_SEC"1";
"A"
$PN"1"50;
"B"
$PN"2"11;
%"UNIVERSAL_GND"
"1","(-11025,4500)","0","logical_power","I20";
;
CDS_LIB"logical_power"
HDL_POWER"GND";
"A"16;
%"UNIVERSAL_GND"
"1","(-10400,4975)","0","logical_power","I23";
;
CDS_LIB"logical_power"
HDL_POWER"GND"
ROOM"VR_CORE0_CTRL";
"A"17;
%"Q_CAP"
"1","(-10400,5225)","0","pure_quanta","I24";
;
PART_NUMBER"CH5222KEB01"
PACK_TYPE"C0402"
MATERIAL"X6S"
TOLERANCE"10%"
VALUE"2.2UF"
VOLTAGE"10V"
LOCATION"PC187"
CDS_LIB"pure_quanta"
LOCATION"PC187"
$SEC"1"
CDS_SEC"1";
"B"
$PN"2"17;
"A"
$PN"1"39;
%"Q_CAP"
"2","(-10200,4600)","0","pure_quanta","I25";
;
PART_NUMBER"CH4104K1B00"
TOLERANCE"10%"
VOLTAGE"25V"
VALUE"0.1UF"
PACK_TYPE"0402"
MATERIAL"X7R"
LOCATION"PC1347"
CDS_LIB"pure_quanta"
$SEC"1"
CDS_SEC"1";
"A"
$PN"1"16;
"B"
$PN"2"40;
%"Q_RES"
"2","(-10400,5625)","0","pure_quanta","I26";
;
PART_NUMBER"CS-2202FB01"
TOLERANCE"1%"
WATTAGE"1/16W"
VALUE"2.2"
MATERIAL"CHIP"
PACK_TYPE"0402LF"
LOCATION"PR101"
CDS_LIB"pure_quanta"
LOCATION"PR101"
$SEC"1"
CDS_SEC"1";
"A"
$PN"1"2;
"B"
$PN"2"39;
%"VCC15"
"1","(-10400,6075)","0","logical_power","I27";
;
HDL_POWER"PVCCFA_EHV_CPU0_PVCC"
CDS_LIB"logical_power";
"A"2;
%"UNIVERSAL_GND"
"1","(-9825,5400)","0","logical_power","I28";
;
CDS_LIB"logical_power"
HDL_POWER"GND"
ROOM"VR_CORE0_CTRL";
"A"18;
%"Q_CAP"
"1","(-9825,5650)","0","pure_quanta","I29";
;
PART_NUMBER"CH5222KEB01"
MATERIAL"X6S"
TOLERANCE"10%"
VOLTAGE"10V"
PACK_TYPE"C0402"
VALUE"2.2UF"
LOCATION"PC2947"
CDS_LIB"pure_quanta"
$SEC"1"
CDS_SEC"1";
"B"
$PN"2"18;
"A"
$PN"1"2;
%"UNIVERSAL_GND"
"1","(-11050,1700)","0","logical_power","I3";
;
CDS_LIB"logical_power"
HDL_POWER"GND";
"A"12;
%"UNIVERSAL_GND"
"1","(-8225,1250)","0","logical_power","I30";
;
CDS_LIB"logical_power"
HDL_POWER"GND"
ROOM"VR_CORE0_CTRL";
"A"19;
%"Q_RES"
"1","(-7300,1725)","0","pure_quanta","I31";
;
PART_NUMBER"CS00002JB13"
PACK_TYPE"0402LF"
MATERIAL"CHIP"
WATTAGE"1/16W"
VALUE"0"
TOLERANCE"5%"
LOCATION"PR1777"
CDS_LIB"pure_quanta"
$SEC"1"
CDS_SEC"1";
"B"
$PN"2"7;
"A"
$PN"1"38;
%"Q_CAP"
"1","(-8075,2875)","0","pure_quanta","I32";
;
PART_NUMBER"TMP_QCH2336K1B12"
VOLTAGE"50V"
MATERIAL"X7R"
TOLERANCE"10%"
VALUE"3300PF"
PACK_TYPE"0402"
LOCATION"PC190_P0_2"
CDS_LIB"pure_quanta"
LOCATION"PC190_P0_2"
$SEC"1"
CDS_SEC"1";
"B"
$PN"2"21;
"A"
$PN"1"3;
%"UNIVERSAL_GND"
"1","(-8225,4050)","0","logical_power","I33";
;
CDS_LIB"logical_power"
HDL_POWER"GND";
"A"20;
%"Q_RES"
"1","(-7525,2425)","0","pure_quanta","I34";
;
PART_NUMBER"CS-3302FB01"
MATERIAL"CHIP"
VALUE"3.3"
WATTAGE"1/16W"
TOLERANCE"1%"
PACK_TYPE"0402LF"
LOCATION"PR1775"
CDS_LIB"pure_quanta"
$SEC"1"
CDS_SEC"1";
"B"
$PN"2"35;
"A"
$PN"1"37;
%"Q_CAP"
"1","(-7675,2875)","0","pure_quanta","I35";
;
PART_NUMBER"CH5103KEB01"
PACK_TYPE"C0402"
TOLERANCE"10%"
MATERIAL"X6S"
VALUE"1UF"
VOLTAGE"16V"
LOCATION"PC192_P0_2"
CDS_LIB"pure_quanta"
LOCATION"PC192_P0_2"
$SEC"1"
CDS_SEC"1";
"B"
$PN"2"21;
"A"
$PN"1"3;
%"Q_CAP"
"1","(-7275,2875)","0","pure_quanta","I36";
;
PART_NUMBER"CH6223MEA01"
TOLERANCE"20%"
PACK_TYPE"C0805"
VALUE"22UF"
MATERIAL"X6S"
VOLTAGE"16V"
LOCATION"PC196_P0_2"
CDS_LIB"pure_quanta"
LOCATION"PC196_P0_2"
$SEC"1"
CDS_SEC"1";
"B"
$PN"2"21;
"A"
$PN"1"3;
%"Q_CAP"
"1","(-6875,2875)","0","pure_quanta","I37";
;
PART_NUMBER"CH6223MEA01"
TOLERANCE"20%"
PACK_TYPE"C0805"
MATERIAL"X6S"
VOLTAGE"16V"
VALUE"22UF"
LOCATION"PC198_P0_2"
CDS_LIB"pure_quanta"
LOCATION"PC198_P0_2"
$SEC"1"
CDS_SEC"1";
"B"
$PN"2"21;
"A"
$PN"1"3;
%"Q_CAP"
"1","(-6700,2250)","2","pure_quanta","I38";
;
PART_NUMBER"CH4106K1B01"
MATERIAL"X7R"
TOLERANCE"10%"
VOLTAGE"50V"
PACK_TYPE"C0402"
VALUE"100NF"
LOCATION"PC194"
CDS_LIB"pure_quanta"
$SEC"1"
CDS_SEC"1";
"B"
$PN"2"36;
"A"
$PN"1"35;
%"Q_INDUCTOR"
"1","(-6450,2000)","0","pure_quanta","I39";
;
PART_NUMBER"CV+12^0EZ03"
MATERIAL"IND"
PACK_TYPE"SMLF"
VALUE"120NH/69A"
LOCATION"PL5"
NEEDS_NO_SIZE"TRUE"
CDS_LIB"pure_quanta"
$SEC"1"
CDS_SEC"1";
"1"
$PN"1"34;
"2"
$PN"2"7;
%"UNIVERSAL_GND"
"1","(-10875,3975)","0","logical_power","I4";
;
CDS_LIB"logical_power"
HDL_POWER"GND";
"A"13;
%"Q_CAP"
"1","(-5475,1775)","0","pure_quanta","I40";
;
PART_NUMBER"CH622KMEA03"
TOLERANCE"20%"
PACK_TYPE"C0805"
VALUE"22UF"
VOLTAGE"4V"
MATERIAL"X6S"
LOCATION"PC203_P0_2"
CDS_LIB"pure_quanta"
LOCATION"PC203_P0_2"
$SEC"1"
CDS_SEC"1";
"B"
$PN"2"25;
"A"
$PN"1"7;
%"Q_CAP"
"1","(-5050,1775)","0","pure_quanta","I41";
;
PART_NUMBER"CH622KMEA03"
TOLERANCE"20%"
VALUE"22UF"
VOLTAGE"4V"
MATERIAL"X6S"
PACK_TYPE"C0805"
LOCATION"PC205_P0_2"
CDS_LIB"pure_quanta"
LOCATION"PC205_P0_2"
$SEC"1"
CDS_SEC"1";
"B"
$PN"2"25;
"A"
$PN"1"7;
%"UNIVERSAL_GND"
"1","(-6275,2450)","0","logical_power","I42";
;
CDS_LIB"logical_power"
HDL_POWER"GND"
ROOM"VR_CORE0_CTRL";
"A"21;
%"VCC15"
"1","(-6275,3250)","0","logical_power","I43";
;
HDL_POWER"SW_P12V_PVCCINFAON_CPU0_FLT"
CDS_LIB"logical_power";
"A"3;
%"UNIVERSAL_GND"
"1","(-4975,4200)","0","logical_power","I44";
;
CDS_LIB"logical_power"
HDL_POWER"GND"
ROOM"VR_CORE0_CTRL";
"A"22;
%"Q_CAP"
"1","(-8075,5675)","0","pure_quanta","I45";
;
PART_NUMBER"TMP_QCH2336K1B12"
MATERIAL"X7R"
VOLTAGE"50V"
VALUE"3300PF"
TOLERANCE"10%"
PACK_TYPE"0402"
LOCATION"PC189_P0_1"
CDS_LIB"pure_quanta"
LOCATION"PC189_P0_1"
$SEC"1"
CDS_SEC"1";
"B"
$PN"2"23;
"A"
$PN"1"4;
%"Q_RES"
"1","(-7325,4525)","0","pure_quanta","I46";
;
PART_NUMBER"CS00002JB13"
WATTAGE"1/16W"
VALUE"0"
TOLERANCE"5%"
MATERIAL"CHIP"
PACK_TYPE"0402LF"
LOCATION"PR1776"
CDS_LIB"pure_quanta"
$SEC"1"
CDS_SEC"1";
"B"
$PN"2"5;
"A"
$PN"1"32;
%"Q_RES"
"1","(-7525,5225)","0","pure_quanta","I47";
;
PART_NUMBER"CS-3302FB01"
VALUE"3.3"
TOLERANCE"1%"
WATTAGE"1/16W"
MATERIAL"CHIP"
PACK_TYPE"0402LF"
LOCATION"PR1774"
CDS_LIB"pure_quanta"
$SEC"1"
CDS_SEC"1";
"B"
$PN"2"29;
"A"
$PN"1"33;
%"Q_CAP"
"1","(-7675,5675)","0","pure_quanta","I48";
;
PART_NUMBER"CH5103KEB01"
VOLTAGE"16V"
TOLERANCE"10%"
PACK_TYPE"C0402"
MATERIAL"X6S"
VALUE"1UF"
LOCATION"PC191_P0_1"
CDS_LIB"pure_quanta"
LOCATION"PC191_P0_1"
$SEC"1"
CDS_SEC"1";
"B"
$PN"2"23;
"A"
$PN"1"4;
%"Q_CAP"
"1","(-7275,5675)","0","pure_quanta","I49";
;
PART_NUMBER"CH6223MEA01"
TOLERANCE"20%"
VALUE"22UF"
MATERIAL"X6S"
VOLTAGE"16V"
PACK_TYPE"C0805"
LOCATION"PC195_P0_1"
CDS_LIB"pure_quanta"
LOCATION"PC195_P0_1"
$SEC"1"
CDS_SEC"1";
"B"
$PN"2"23;
"A"
$PN"1"4;
%"Q_RES"
"2","(-10875,4200)","2","pure_quanta","I5";
;
PART_NUMBER"CS28872FB01"
PACK_TYPE"0402LF"
WATTAGE"1/16W"
MATERIAL"EMPTY"
TOLERANCE"1%"
VALUE"8.87K"
LOCATION"PR1708"
CDS_LIB"pure_quanta"
$SEC"1"
CDS_SEC"1";
"A"
$PN"1"43;
"B"
$PN"2"13;
%"Q_CAP"
"1","(-6875,5675)","0","pure_quanta","I50";
;
PART_NUMBER"CH6223MEA01"
TOLERANCE"20%"
MATERIAL"X6S"
VALUE"22UF"
VOLTAGE"16V"
PACK_TYPE"C0805"
LOCATION"PC197_P0_1"
CDS_LIB"pure_quanta"
LOCATION"PC197_P0_1"
$SEC"1"
CDS_SEC"1";
"B"
$PN"2"23;
"A"
$PN"1"4;
%"Q_CAP"
"1","(-6700,5050)","2","pure_quanta","I51";
;
PART_NUMBER"CH4106K1B01"
MATERIAL"X7R"
TOLERANCE"10%"
VALUE"100NF"
VOLTAGE"50V"
PACK_TYPE"C0402"
LOCATION"PC193"
CDS_LIB"pure_quanta"
$SEC"1"
CDS_SEC"1";
"B"
$PN"2"30;
"A"
$PN"1"29;
%"Q_INDUCTOR"
"1","(-6450,4800)","0","pure_quanta","I52";
;
PART_NUMBER"CV+12^0EZ03"
MATERIAL"IND"
VALUE"120NH/69A"
PACK_TYPE"SMLF"
LOCATION"PL4"
CDS_LIB"pure_quanta"
NEEDS_NO_SIZE"TRUE"
$SEC"1"
CDS_SEC"1";
"1"
$PN"1"31;
"2"
$PN"2"5;
%"UNIVERSAL_GND"
"1","(-6275,5250)","0","logical_power","I53";
;
CDS_LIB"logical_power"
HDL_POWER"GND"
ROOM"VR_CORE0_CTRL";
"A"23;
%"Q_CAP"
"1","(-6100,4575)","0","pure_quanta","I54";
;
PART_NUMBER"CH4106K1B01"
VALUE"100NF"
VOLTAGE"50V"
TOLERANCE"10%"
PACK_TYPE"C0402"
MATERIAL"X7R"
LOCATION"PC199_P0_1"
CDS_LIB"pure_quanta"
LOCATION"PC199_P0_1"
$SEC"1"
CDS_SEC"1";
"B"
$PN"2"22;
"A"
$PN"1"5;
%"VCC15"
"1","(-6275,6050)","0","logical_power","I55";
;
HDL_POWER"SW_P12V_PVCCINFAON_CPU0_FLT"
CDS_LIB"logical_power";
"A"4;
%"Q_CAP"
"1","(-5700,4575)","0","pure_quanta","I56";
;
PART_NUMBER"CH622KMEA03"
TOLERANCE"20%"
VOLTAGE"4V"
MATERIAL"X6S"
VALUE"22UF"
PACK_TYPE"C0805"
LOCATION"PC202_P0_1"
CDS_LIB"pure_quanta"
LOCATION"PC202_P0_1"
$SEC"1"
CDS_SEC"1";
"B"
$PN"2"22;
"A"
$PN"1"5;
%"Q_CAP"
"1","(-5275,4575)","0","pure_quanta","I57";
;
PART_NUMBER"CH622KMEA03"
TOLERANCE"20%"
VOLTAGE"4V"
VALUE"22UF"
MATERIAL"X6S"
PACK_TYPE"C0805"
LOCATION"PC204_P0_1"
CDS_LIB"pure_quanta"
LOCATION"PC204_P0_1"
$SEC"1"
CDS_SEC"1";
"B"
$PN"2"22;
"A"
$PN"1"5;
%"VCC15"
"1","(-4975,4975)","0","logical_power","I58";
;
HDL_POWER"PVCCINFAON_CPU0"
CDS_LIB"logical_power";
"A"5;
%"GND"
"1","(-5025,5650)","0","logical_power","I59";
;
CDS_LIB"logical_power"
SIZE"1B"
HDL_POWER"GND";
"A<SIZE-1..0>\NAC"24;
%"Q_CAP"
"1","(-5025,5900)","0","pure_quanta","I60";
;
PART_NUMBER"CH4106K1B01"
PACK_TYPE"C0402"
VALUE"100NF"
MATERIAL"X7R"
VOLTAGE"50V"
TOLERANCE"10%"
LOCATION"PC1655"
CDS_LIB"pure_quanta"
$SEC"1"
CDS_SEC"1";
"B"
$PN"2"24;
"A"
$PN"1"6;
%"VCC15"
"1","(-5025,6275)","0","logical_power","I61";
;
HDL_POWER"P12V_AUX"
CDS_LIB"logical_power";
"A"6;
%"Q_INDUCTOR"
"1","(-4600,6125)","0","pure_quanta","I62";
;
PART_NUMBER"CV+10G0MZ04"
PACK_TYPE"SMLF"
VALUE"100NH/16A"
MATERIAL"IND"
LOCATION"PL6"
NEEDS_NO_SIZE"TRUE"
CDS_LIB"pure_quanta"
LOCATION"PL6"
$SEC"1"
CDS_SEC"1";
"1"
$PN"1"6;
"2"
$PN"2"9;
%"Q_RES"
"2","(-4575,1775)","0","pure_quanta","I63";
;
PART_NUMBER"CS14992FB06"
TOLERANCE"1%"
MATERIAL"CHIP"
WATTAGE"1/16W"
PACK_TYPE"0402LF"
VALUE"499"
LOCATION"PR4226"
BOM_COST"VR_PCH"
CDS_LIB"pure_quanta"
$SEC"1"
CDS_SEC"1";
"A"
$PN"1"7;
"B"
$PN"2"25;
%"UNIVERSAL_GND"
"1","(-4250,1400)","0","logical_power","I64";
;
CDS_LIB"logical_power"
HDL_POWER"GND"
ROOM"VR_CORE0_CTRL";
"A"25;
%"VCC15"
"1","(-4250,2150)","0","logical_power","I65";
;
HDL_POWER"PVCCINFAON_CPU0"
CDS_LIB"logical_power";
"A"7;
%"Q_CAPP"
"1","(-4325,3125)","0","pure_quanta","I66";
;
PART_NUMBER"CC7560JMD16"
PACK_TYPE"THLF"
VALUE"560UF"
TOLERANCE"20%"
MATERIAL"OSCON"
VOLTAGE"2.5V"
LOCATION"PC1574"
CDS_LIB"pure_quanta"
$SEC"1"
CDS_SEC"1";
"A"
$PN"1"8;
"B"
$PN"2"26;
%"Q_CAPP"
"1","(-3750,3125)","0","pure_quanta","I67";
;
PART_NUMBER"CC7560JMD16"
PACK_TYPE"THLF"
VALUE"560UF"
TOLERANCE"20%"
MATERIAL"OSCON"
VOLTAGE"2.5V"
LOCATION"PC1576"
CDS_LIB"pure_quanta"
$SEC"1"
CDS_SEC"1";
"A"
$PN"1"8;
"B"
$PN"2"26;
%"Q_CAPP"
"1","(-4325,4050)","0","pure_quanta","I68";
;
PART_NUMBER"CH733RY8807"
MATERIAL"SPCAP"
TOLERANCE"35%"
VALUE"330UF"
VOLTAGE"2V"
PACK_TYPE"SMLF"
LOCATION"PC1573"
CDS_LIB"pure_quanta"
$SEC"1"
CDS_SEC"1";
"A"
$PN"1"10;
"B"
$PN"2"27;
%"Q_CAPP"
"1","(-3750,4050)","0","pure_quanta","I69";
;
PART_NUMBER"CH733RY8807"
MATERIAL"SPCAP"
TOLERANCE"35%"
VALUE"330UF"
VOLTAGE"2V"
PACK_TYPE"SMLF"
LOCATION"PC1575"
CDS_LIB"pure_quanta"
$SEC"1"
CDS_SEC"1";
"A"
$PN"1"10;
"B"
$PN"2"27;
%"Q_CAPP"
"1","(-3175,3125)","0","pure_quanta","I70";
;
PART_NUMBER"CC7560JMD16"
PACK_TYPE"THLF"
VALUE"560UF"
TOLERANCE"20%"
MATERIAL"OSCON"
VOLTAGE"2.5V"
LOCATION"PC1579"
CDS_LIB"pure_quanta"
$SEC"1"
CDS_SEC"1";
"A"
$PN"1"8;
"B"
$PN"2"26;
%"UNIVERSAL_GND"
"1","(-2575,2800)","0","logical_power","I71";
;
CDS_LIB"logical_power"
HDL_POWER"GND"
ROOM"VR_CORE0_CTRL";
"A"26;
%"VCC15"
"1","(-2575,3450)","0","logical_power","I72";
;
HDL_POWER"PVCCINFAON_CPU0"
CDS_LIB"logical_power";
"A"8;
%"UNIVERSAL_GND"
"1","(-2575,3725)","0","logical_power","I73";
;
CDS_LIB"logical_power"
HDL_POWER"GND"
ROOM"VR_CORE0_CTRL";
"A"27;
%"Q_CAPP"
"1","(-4275,5900)","0","pure_quanta","I74";
;
PART_NUMBER"CC72703MD38"
PACK_TYPE"THLF"
TOLERANCE"20%"
MATERIAL"OSCON"
VOLTAGE"16V"
VALUE"270UF"
LOCATION"PC207"
CDS_LIB"pure_quanta"
LOCATION"PC207"
$SEC"1"
CDS_SEC"1";
"A"
$PN"1"9;
"B"
$PN"2"28;
%"Q_CAPP"
"1","(-3875,5900)","0","pure_quanta","I75";
;
PART_NUMBER"CC72703MD38"
PACK_TYPE"THLF"
TOLERANCE"20%"
MATERIAL"OSCON"
VOLTAGE"16V"
VALUE"270UF"
LOCATION"PC208"
CDS_LIB"pure_quanta"
LOCATION"PC208"
$SEC"1"
CDS_SEC"1";
"A"
$PN"1"9;
"B"
$PN"2"28;
%"UNIVERSAL_GND"
"1","(-2675,5575)","0","logical_power","I76";
;
CDS_LIB"logical_power"
HDL_POWER"GND"
ROOM"VR_CORE0_CTRL";
"A"28;
%"VCC15"
"1","(-2675,6225)","0","logical_power","I77";
;
HDL_POWER"SW_P12V_PVCCINFAON_CPU0_FLT"
CDS_LIB"logical_power";
"A"9;
%"VCC15"
"1","(-2575,4375)","0","logical_power","I78";
;
HDL_POWER"PVCCINFAON_CPU0"
CDS_LIB"logical_power";
"A"10;
%"ISL99390FRZTR5935"
"1","(-8725,4775)","0","pure_quanta","I79";
;
PART_NUMBER"AL099390004"
MATERIAL"IC"
PART_TYPE"SMLF"
VALUE"ISL99390FRZ-TR5935"
LOCATION"PU43_P0_1"
CDS_LIB"pure_quanta"
CDS_LMAN_SYM_OUTLINE"-300,700,250,-650"
NEEDS_NO_SIZE"TRUE"
SEC_TYPE""
SEC"1";
"PGND2"
$PN"7_9-20_24"20;
"GL2"
$PN"41"0;
"GL1"
$PN"6"0;
"DNC"
$PN"31"0;
"EN"
$PN"35"39;
"PGND3"
$PN"40"20;
"VOS"
$PN"1"32;
"VIN2"
$PN"30"4;
"PGND1"
$PN"5"20;
"SW"
$PN"10_19"31;
"LSET"
$PN"37"43;
"IOUT"
$PN"38"41;
"TOUT_FLT"
$PN"36"42;
"PVCC"
$PN"4"2;
"PHASE"
$PN"32"30;
"VIN1"
$PN"25_29"4;
"BOOT"
$PN"33"33;
"AGND"
$PN"2"20;
"VCC"
$PN"3"39;
"REFIN"
$PN"39"40;
"PWM"
$PN"34"44;
END.
